(kicad_pcb
	(version 20260206)
	(generator "pcbnew")
	(generator_version "10.0")
	(general
		(thickness 1.6)
		(legacy_teardrops no)
	)
	(paper "A4")
	(title_block
		(title "Wiwynn_Tioga_Pass_MB.brd")
		(comment 1 "Tioga Pass / footprints 3691-3697 of 4770")
	)
	(layers
		(0 "F.Cu" signal "TOP")
		(4 "In1.Cu" signal "L2GND")
		(6 "In2.Cu" signal "L3")
		(8 "In3.Cu" signal "L4GND")
		(10 "In4.Cu" signal "L5")
		(12 "In5.Cu" signal "L6GND")
		(14 "In6.Cu" signal "L7VCC")
		(16 "In7.Cu" signal "L8VCC")
		(18 "In8.Cu" signal "L9GND")
		(20 "In9.Cu" signal "L10")
		(22 "In10.Cu" signal "L11GND")
		(24 "In11.Cu" signal "L12")
		(26 "In12.Cu" signal "L13GND")
		(2 "B.Cu" signal "BOTTOM")
		(9 "F.Adhes" user "F.Adhesive")
		(11 "B.Adhes" user "B.Adhesive")
		(13 "F.Paste" user "Package Geometry/Pastemask Top")
		(15 "B.Paste" user "Package Geometry/Pastemask Bottom")
		(5 "F.SilkS" user "Ref Des/Silkscreen Top")
		(7 "B.SilkS" user "Ref Des/Silkscreen Bottom")
		(1 "F.Mask" user "Board Geometry/Soldermask Top")
		(3 "B.Mask" user "Board Geometry/Soldermask Bottom")
		(17 "Dwgs.User" user "User.Drawings")
		(19 "Cmts.User" user "User.Comments")
		(21 "Eco1.User" user "User.Eco1")
		(23 "Eco2.User" user "User.Eco2")
		(25 "Edge.Cuts" user "Board Geometry/Outline")
		(27 "Margin" user)
		(31 "F.CrtYd" user "Package Geometry/Place Bound Top")
		(29 "B.CrtYd" user "Package Geometry/Place Bound Bottom")
		(35 "F.Fab" user "Ref Des/Assembly Top")
		(33 "B.Fab" user "Ref Des/Assembly Bottom")
	)
	(footprint ""
		(layer "B.Cu")
		(at 450.5325 -22.733 -90)
		(property "Reference" "R6W20"
			(at 0.8382 -0.67818 270)
			(unlocked yes)
			(layer "B.SilkS")
			(effects
				(font
					(size 0.4064 0.254)
					(thickness 0.1524)
				)
				(justify left mirror)
			)
		)
		(property "Value" ""
			(at 0 0 90)
			(layer "B.Fab")
			(effects
				(font
					(size 1.27 1.27)
				)
				(justify mirror)
			)
		)
		(duplicate_pad_numbers_are_jumpers no)
		(fp_poly
			(pts
				(xy 0.2794 -0.1016) (xy -0.2794 -0.1016) (xy -0.2794 0.9906) (xy 0.2794 0.9906)
			)
			(stroke
				(width 0)
				(type default)
			)
			(fill no)
			(layer "B.CrtYd")
		)
		(fp_line
			(start -0.2794 0.9906)
			(end -0.2794 -0.1016)
			(stroke
				(width 0.1)
				(type default)
			)
			(layer "B.Fab")
		)
		(fp_line
			(start 0.2794 0.9906)
			(end -0.2794 0.9906)
			(stroke
				(width 0.1)
				(type default)
			)
			(layer "B.Fab")
		)
		(fp_line
			(start -0.2794 -0.1016)
			(end 0.2794 -0.1016)
			(stroke
				(width 0.1)
				(type default)
			)
			(layer "B.Fab")
		)
		(fp_line
			(start 0.2794 -0.1016)
			(end 0.2794 0.9906)
			(stroke
				(width 0.1)
				(type default)
			)
			(layer "B.Fab")
		)
		(pad "1" smd rect
			(at 0 0 90)
			(size 0.508 0.508)
			(layers "B.Cu" "B.Mask" "B.Paste")
			(net "SMB_HOST_STBY_LVC3_SDA_R3")
		)
		(pad "2" smd rect
			(at 0 0.889 90)
			(size 0.508 0.508)
			(layers "B.Cu" "B.Mask" "B.Paste")
			(net "SMB_HOST_STBY_LVC3_SDA")
		)
		(zone
			(layer "B.Cu")
			(hatch none 0.5)
			(connect_pads
				(clearance 0)
			)
			(min_thickness 0.25)
			(keepout
				(tracks not_allowed)
				(vias allowed)
				(pads allowed)
				(copperpour not_allowed)
				(footprints allowed)
			)
			(placement
				(enabled no)
				(sheetname "")
			)
			(fill
				(thermal_gap 0.5)
				(thermal_bridge_width 0.5)
				(island_removal_mode 0)
			)
			(polygon
				(pts
					(xy 449.8975 -22.479) (xy 449.8975 -22.987) (xy 450.2785 -22.987) (xy 450.2785 -22.479)
				)
			)
		)
		(zone
			(layer "B.Cu")
			(hatch none 0.5)
			(connect_pads
				(clearance 0)
			)
			(min_thickness 0.25)
			(keepout
				(tracks allowed)
				(vias not_allowed)
				(pads allowed)
				(copperpour not_allowed)
				(footprints allowed)
			)
			(placement
				(enabled no)
				(sheetname "")
			)
			(fill
				(thermal_gap 0.5)
				(thermal_bridge_width 0.5)
				(island_removal_mode 0)
			)
			(polygon
				(pts
					(xy 450.2785 -22.479) (xy 450.2785 -22.987) (xy 449.8975 -22.987) (xy 449.8975 -22.479)
				)
			)
		)
	)
	(footprint ""
		(layer "B.Cu")
		(at 413.5755 -18.288 -90)
		(property "Reference" "R2U46"
			(at 0 0 90)
			(layer "B.SilkS")
			(hide yes)
			(effects
				(font
					(size 1.27 1.27)
				)
				(justify mirror)
			)
		)
		(property "Value" ""
			(at 0 0 90)
			(layer "B.Fab")
			(effects
				(font
					(size 1.27 1.27)
				)
				(justify mirror)
			)
		)
		(duplicate_pad_numbers_are_jumpers no)
		(fp_poly
			(pts
				(xy 0.2794 -0.1016) (xy -0.2794 -0.1016) (xy -0.2794 0.9906) (xy 0.2794 0.9906)
			)
			(stroke
				(width 0)
				(type default)
			)
			(fill no)
			(layer "B.CrtYd")
		)
		(fp_line
			(start -0.2794 0.9906)
			(end -0.2794 -0.1016)
			(stroke
				(width 0.1)
				(type default)
			)
			(layer "B.Fab")
		)
		(fp_line
			(start 0.2794 0.9906)
			(end -0.2794 0.9906)
			(stroke
				(width 0.1)
				(type default)
			)
			(layer "B.Fab")
		)
		(fp_line
			(start -0.2794 -0.1016)
			(end 0.2794 -0.1016)
			(stroke
				(width 0.1)
				(type default)
			)
			(layer "B.Fab")
		)
		(fp_line
			(start 0.2794 -0.1016)
			(end 0.2794 0.9906)
			(stroke
				(width 0.1)
				(type default)
			)
			(layer "B.Fab")
		)
		(pad "1" smd rect
			(at 0 0 90)
			(size 0.508 0.508)
			(layers "B.Cu" "B.Mask" "B.Paste")
			(net "H_CPU1_MEMKLM_MEMHOT_LVT3_N")
		)
		(pad "2" smd rect
			(at 0 0.889 90)
			(size 0.508 0.508)
			(layers "B.Cu" "B.Mask" "B.Paste")
			(net "H_CPU1_MEMKLM_MEMHOT_LVT3_BMC_N")
		)
		(zone
			(layer "B.Cu")
			(hatch none 0.5)
			(connect_pads
				(clearance 0)
			)
			(min_thickness 0.25)
			(keepout
				(tracks not_allowed)
				(vias allowed)
				(pads allowed)
				(copperpour not_allowed)
				(footprints allowed)
			)
			(placement
				(enabled no)
				(sheetname "")
			)
			(fill
				(thermal_gap 0.5)
				(thermal_bridge_width 0.5)
				(island_removal_mode 0)
			)
			(polygon
				(pts
					(xy 412.9405 -18.034) (xy 412.9405 -18.542) (xy 413.3215 -18.542) (xy 413.3215 -18.034)
				)
			)
		)
		(zone
			(layer "B.Cu")
			(hatch none 0.5)
			(connect_pads
				(clearance 0)
			)
			(min_thickness 0.25)
			(keepout
				(tracks allowed)
				(vias not_allowed)
				(pads allowed)
				(copperpour not_allowed)
				(footprints allowed)
			)
			(placement
				(enabled no)
				(sheetname "")
			)
			(fill
				(thermal_gap 0.5)
				(thermal_bridge_width 0.5)
				(island_removal_mode 0)
			)
			(polygon
				(pts
					(xy 413.3215 -18.034) (xy 413.3215 -18.542) (xy 412.9405 -18.542) (xy 412.9405 -18.034)
				)
			)
		)
	)
	(footprint ""
		(layer "B.Cu")
		(at 32.2834 -78.9432 90)
		(property "Reference" "R9P8"
			(at 0 0 90)
			(layer "B.SilkS")
			(hide yes)
			(effects
				(font
					(size 1.27 1.27)
				)
				(justify mirror)
			)
		)
		(property "Value" ""
			(at 0 0 90)
			(layer "B.Fab")
			(effects
				(font
					(size 1.27 1.27)
				)
				(justify mirror)
			)
		)
		(duplicate_pad_numbers_are_jumpers no)
		(fp_poly
			(pts
				(xy 0.2794 -0.1016) (xy -0.2794 -0.1016) (xy -0.2794 0.9906) (xy 0.2794 0.9906)
			)
			(stroke
				(width 0)
				(type default)
			)
			(fill no)
			(layer "B.CrtYd")
		)
		(fp_line
			(start 0.2794 -0.1016)
			(end 0.2794 0.9906)
			(stroke
				(width 0.1)
				(type default)
			)
			(layer "B.Fab")
		)
		(fp_line
			(start -0.2794 -0.1016)
			(end 0.2794 -0.1016)
			(stroke
				(width 0.1)
				(type default)
			)
			(layer "B.Fab")
		)
		(fp_line
			(start 0.2794 0.9906)
			(end -0.2794 0.9906)
			(stroke
				(width 0.1)
				(type default)
			)
			(layer "B.Fab")
		)
		(fp_line
			(start -0.2794 0.9906)
			(end -0.2794 -0.1016)
			(stroke
				(width 0.1)
				(type default)
			)
			(layer "B.Fab")
		)
		(pad "1" smd rect
			(at 0 0 270)
			(size 0.508 0.508)
			(layers "B.Cu" "B.Mask" "B.Paste")
			(net "VR_PVCCIN_CPU1_PH4_VCIN")
		)
		(pad "2" smd rect
			(at 0 0.889 270)
			(size 0.508 0.508)
			(layers "B.Cu" "B.Mask" "B.Paste")
			(net "P5V_STBY")
		)
		(zone
			(layer "B.Cu")
			(hatch none 0.5)
			(connect_pads
				(clearance 0)
			)
			(min_thickness 0.25)
			(keepout
				(tracks allowed)
				(vias not_allowed)
				(pads allowed)
				(copperpour not_allowed)
				(footprints allowed)
			)
			(placement
				(enabled no)
				(sheetname "")
			)
			(fill
				(thermal_gap 0.5)
				(thermal_bridge_width 0.5)
				(island_removal_mode 0)
			)
			(polygon
				(pts
					(xy 32.5374 -79.1972) (xy 32.5374 -78.6892) (xy 32.9184 -78.6892) (xy 32.9184 -79.1972)
				)
			)
		)
		(zone
			(layer "B.Cu")
			(hatch none 0.5)
			(connect_pads
				(clearance 0)
			)
			(min_thickness 0.25)
			(keepout
				(tracks not_allowed)
				(vias allowed)
				(pads allowed)
				(copperpour not_allowed)
				(footprints allowed)
			)
			(placement
				(enabled no)
				(sheetname "")
			)
			(fill
				(thermal_gap 0.5)
				(thermal_bridge_width 0.5)
				(island_removal_mode 0)
			)
			(polygon
				(pts
					(xy 32.9184 -79.1972) (xy 32.9184 -78.6892) (xy 32.5374 -78.6892) (xy 32.5374 -79.1972)
				)
			)
		)
	)
	(footprint ""
		(layer "B.Cu")
		(at 410.455872 -6.0452 -90)
		(property "Reference" "U8D8"
			(at -0.621538 1.822958 90)
			(unlocked yes)
			(layer "B.SilkS")
			(effects
				(font
					(size 0.7874 0.5842)
					(thickness 0.1524)
				)
				(justify mirror)
			)
		)
		(property "Value" ""
			(at 0 0 90)
			(layer "B.Fab")
			(effects
				(font
					(size 1.27 1.27)
				)
				(justify mirror)
			)
		)
		(duplicate_pad_numbers_are_jumpers no)
		(fp_circle
			(center 1.0795 -0.054102)
			(end 1.0795 -0.180848)
			(stroke
				(width 0.254)
				(type default)
			)
			(fill no)
			(layer "B.SilkS")
		)
		(fp_rect
			(start 0.216154 1.27508)
			(end -1.333754 -0.275082)
			(stroke
				(width 0)
				(type default)
			)
			(fill no)
			(layer "B.CrtYd")
		)
		(fp_line
			(start -1.333754 1.27508)
			(end 0.216154 1.27508)
			(stroke
				(width 0.1)
				(type default)
			)
			(layer "B.Fab")
		)
		(fp_line
			(start 0.216154 1.27508)
			(end 0.216154 -0.275082)
			(stroke
				(width 0.1)
				(type default)
			)
			(layer "B.Fab")
		)
		(fp_line
			(start -1.333754 -0.275082)
			(end -1.333754 1.27508)
			(stroke
				(width 0.1)
				(type default)
			)
			(layer "B.Fab")
		)
		(fp_line
			(start 0.216154 -0.275082)
			(end -1.333754 -0.275082)
			(stroke
				(width 0.1)
				(type default)
			)
			(layer "B.Fab")
		)
		(fp_circle
			(center 1.0795 -0.054102)
			(end 1.0795 -0.180848)
			(stroke
				(width 0.254)
				(type default)
			)
			(fill no)
			(layer "B.Fab")
		)
		(pad "1" smd rect
			(at 0 0 90)
			(size 0.9398 0.3048)
			(layers "B.Cu" "B.Mask" "B.Paste")
			(net "PWRGD_P5V_N")
		)
		(pad "2" smd rect
			(at 0.0254 0.500126 90)
			(size 0.889 0.3048)
			(layers "B.Cu" "B.Mask" "B.Paste")
			(net "P3V3_STBY")
		)
		(pad "3" smd rect
			(at 0.0254 0.999998 90)
			(size 0.889 0.3048)
			(layers "B.Cu" "B.Mask" "B.Paste")
			(net "A_PG_P5V")
		)
		(pad "4" smd rect
			(at -1.143 0.999998 90)
			(size 0.889 0.3048)
			(layers "B.Cu" "B.Mask" "B.Paste")
			(net "A_PG_P12V_MAIN")
		)
		(pad "5" smd rect
			(at -1.143 0.500126 90)
			(size 0.889 0.3048)
			(layers "B.Cu" "B.Mask" "B.Paste")
			(net "GND")
		)
		(pad "6" smd rect
			(at -1.143 0 90)
			(size 0.889 0.3048)
			(layers "B.Cu" "B.Mask" "B.Paste")
			(net "PWRGD_P12V_MAIN_R")
		)
	)
	(footprint ""
		(layer "B.Cu")
		(at 3.499104 -15.15237 90)
		(property "Reference" "R9U12"
			(at 0 0 90)
			(layer "B.SilkS")
			(hide yes)
			(effects
				(font
					(size 1.27 1.27)
				)
				(justify mirror)
			)
		)
		(property "Value" ""
			(at 0 0 90)
			(layer "B.Fab")
			(effects
				(font
					(size 1.27 1.27)
				)
				(justify mirror)
			)
		)
		(duplicate_pad_numbers_are_jumpers no)
		(fp_rect
			(start 0.2794 -0.1016)
			(end -0.2794 0.9906)
			(stroke
				(width 0)
				(type default)
			)
			(fill no)
			(layer "B.CrtYd")
		)
		(fp_line
			(start 0.2794 -0.1016)
			(end 0.2794 0.9906)
			(stroke
				(width 0.1)
				(type default)
			)
			(layer "B.Fab")
		)
		(fp_line
			(start -0.2794 -0.1016)
			(end 0.2794 -0.1016)
			(stroke
				(width 0.1)
				(type default)
			)
			(layer "B.Fab")
		)
		(fp_line
			(start 0.2794 0.9906)
			(end -0.2794 0.9906)
			(stroke
				(width 0.1)
				(type default)
			)
			(layer "B.Fab")
		)
		(fp_line
			(start -0.2794 0.9906)
			(end -0.2794 -0.1016)
			(stroke
				(width 0.1)
				(type default)
			)
			(layer "B.Fab")
		)
		(pad "1" smd rect
			(at 0 0 270)
			(size 0.508 0.508)
			(layers "B.Cu" "B.Mask" "B.Paste")
			(net "VR_PVDDQ_GHJ_PH2_VCIN")
		)
		(pad "2" smd rect
			(at 0 0.889 270)
			(size 0.508 0.508)
			(layers "B.Cu" "B.Mask" "B.Paste")
			(net "P5V_STBY")
		)
		(zone
			(layer "B.Cu")
			(hatch none 0.5)
			(connect_pads
				(clearance 0)
			)
			(min_thickness 0.25)
			(keepout
				(tracks not_allowed)
				(vias allowed)
				(pads allowed)
				(copperpour not_allowed)
				(footprints allowed)
			)
			(placement
				(enabled no)
				(sheetname "")
			)
			(fill
				(thermal_gap 0.5)
				(thermal_bridge_width 0.5)
				(island_removal_mode 0)
			)
			(polygon
				(pts
					(xy 3.753104 -15.40637) (xy 3.753104 -14.89837) (xy 4.134104 -14.89837) (xy 4.134104 -15.40637)
				)
			)
		)
		(zone
			(layer "B.Cu")
			(hatch none 0.5)
			(connect_pads
				(clearance 0)
			)
			(min_thickness 0.25)
			(keepout
				(tracks allowed)
				(vias not_allowed)
				(pads allowed)
				(copperpour not_allowed)
				(footprints allowed)
			)
			(placement
				(enabled no)
				(sheetname "")
			)
			(fill
				(thermal_gap 0.5)
				(thermal_bridge_width 0.5)
				(island_removal_mode 0)
			)
			(polygon
				(pts
					(xy 3.753104 -15.40637) (xy 3.753104 -14.89837) (xy 4.134104 -14.89837) (xy 4.134104 -15.40637)
				)
			)
		)
	)
	(footprint ""
		(layer "B.Cu")
		(at 33.622996 -77.552042 90)
		(property "Reference" "C1D5"
			(at 0 0 90)
			(layer "B.SilkS")
			(hide yes)
			(effects
				(font
					(size 1.27 1.27)
				)
				(justify mirror)
			)
		)
		(property "Value" "*"
			(at -1.1811 -2.8194 90)
			(unlocked yes)
			(layer "B.Fab")
			(hide yes)
			(effects
				(font
					(size 1.27 1.016)
					(thickness 0.1524)
				)
				(justify mirror)
			)
		)
		(property "Device Type" "SC1U10V2KX-4-GP_SMD-BCG6-SC1U1A"
			(at -1.1811 -4.3434 90)
			(unlocked yes)
			(layer "B.Fab")
			(hide yes)
			(effects
				(font
					(size 1.27 1.016)
					(thickness 0.1524)
				)
				(justify mirror)
			)
		)
		(duplicate_pad_numbers_are_jumpers no)
		(fp_rect
			(start 0.4318 0.9525)
			(end -0.4318 -0.9525)
			(stroke
				(width 0)
				(type default)
			)
			(fill no)
			(layer "B.CrtYd")
		)
		(fp_rect
			(start 0.4318 0.9525)
			(end -0.4318 -0.9525)
			(stroke
				(width 0)
				(type default)
			)
			(fill no)
			(layer "B.Fab")
		)
		(pad "1" smd custom
			(at 0 -0.4445 270)
			(size 0.1524 0.1524)
			(layers "B.Cu" "B.Mask" "B.Paste")
			(net "P5V_STBY")
			(options
				(clearance outline)
				(anchor circle)
			)
			(primitives
				(gr_poly
					(pts
						(arc
							(start 0.3048 0.2032)
							(mid 0.275042 0.275042)
							(end 0.2032 0.3048)
						)
						(arc
							(start -0.2032 0.3048)
							(mid -0.275042 0.275042)
							(end -0.3048 0.2032)
						)
						(arc
							(start -0.3048 -0.2032)
							(mid -0.275042 -0.275042)
							(end -0.2032 -0.3048)
						)
						(arc
							(start 0.2032 -0.3048)
							(mid 0.275042 -0.275042)
							(end 0.3048 -0.2032)
						)
					)
					(width 0)
					(fill yes)
				)
			)
		)
		(pad "2" smd custom
			(at 0 0.4445 270)
			(size 0.1524 0.1524)
			(layers "B.Cu" "B.Mask" "B.Paste")
			(net "GND")
			(options
				(clearance outline)
				(anchor circle)
			)
			(primitives
				(gr_poly
					(pts
						(arc
							(start 0.3048 0.2032)
							(mid 0.275042 0.275042)
							(end 0.2032 0.3048)
						)
						(arc
							(start -0.2032 0.3048)
							(mid -0.275042 0.275042)
							(end -0.3048 0.2032)
						)
						(arc
							(start -0.3048 -0.2032)
							(mid -0.275042 -0.275042)
							(end -0.2032 -0.3048)
						)
						(arc
							(start 0.2032 -0.3048)
							(mid 0.275042 -0.275042)
							(end 0.3048 -0.2032)
						)
					)
					(width 0)
					(fill yes)
				)
			)
		)
	)
	(footprint ""
		(layer "B.Cu")
		(at 80.757268 -8.1534 -90)
		(property "Reference" "C8U7"
			(at -1.848866 0.752348 270)
			(unlocked yes)
			(layer "B.SilkS")
			(effects
				(font
					(size 1.27 0.9652)
					(thickness 0.1524)
				)
				(justify mirror)
			)
		)
		(property "Value" ""
			(at 0 0 90)
			(layer "B.Fab")
			(effects
				(font
					(size 1.27 1.27)
				)
				(justify mirror)
			)
		)
		(duplicate_pad_numbers_are_jumpers no)
		(fp_rect
			(start 0.500126 1.598422)
			(end -0.500126 -0.201422)
			(stroke
				(width 0)
				(type default)
			)
			(fill no)
			(layer "B.CrtYd")
		)
		(fp_line
			(start -0.500126 1.598422)
			(end 0.500126 1.598422)
			(stroke
				(width 0.1)
				(type default)
			)
			(layer "B.Fab")
		)
		(fp_line
			(start 0.500126 1.598422)
			(end 0.500126 -0.201422)
			(stroke
				(width 0.1)
				(type default)
			)
			(layer "B.Fab")
		)
		(fp_line
			(start -0.500126 -0.201422)
			(end -0.500126 1.598422)
			(stroke
				(width 0.1)
				(type default)
			)
			(layer "B.Fab")
		)
		(fp_line
			(start 0.500126 -0.201422)
			(end -0.500126 -0.201422)
			(stroke
				(width 0.1)
				(type default)
			)
			(layer "B.Fab")
		)
		(pad "1" smd rect
			(at 0 0 180)
			(size 0.889 0.9906)
			(layers "B.Cu" "B.Mask" "B.Paste")
			(net "PVDDQ_GHJ")
		)
		(pad "2" smd rect
			(at 0 1.397 180)
			(size 0.889 0.9906)
			(layers "B.Cu" "B.Mask" "B.Paste")
			(net "GND")
		)
		(zone
			(layer "B.Cu")
			(hatch none 0.5)
			(connect_pads
				(clearance 0)
			)
			(min_thickness 0.25)
			(keepout
				(tracks not_allowed)
				(vias allowed)
				(pads allowed)
				(copperpour not_allowed)
				(footprints allowed)
			)
			(placement
				(enabled no)
				(sheetname "")
			)
			(fill
				(thermal_gap 0.5)
				(thermal_bridge_width 0.5)
				(island_removal_mode 0)
			)
			(polygon
				(pts
					(xy 79.804768 -7.6581) (xy 80.312768 -7.6581) (xy 80.312768 -8.6487) (xy 79.804768 -8.6487)
				)
			)
		)
		(zone
			(layer "B.Cu")
			(hatch none 0.5)
			(connect_pads
				(clearance 0)
			)
			(min_thickness 0.25)
			(keepout
				(tracks allowed)
				(vias not_allowed)
				(pads allowed)
				(copperpour not_allowed)
				(footprints allowed)
			)
			(placement
				(enabled no)
				(sheetname "")
			)
			(fill
				(thermal_gap 0.5)
				(thermal_bridge_width 0.5)
				(island_removal_mode 0)
			)
			(polygon
				(pts
					(xy 79.804768 -7.6581) (xy 80.312768 -7.6581) (xy 80.312768 -8.6487) (xy 79.804768 -8.6487)
				)
			)
		)
	)
)
